FILE_TYPE = CONNECTIVITY;
{Allegro Design Entry HDL 17.2-2016 S066 (3851973) 4/6/2020}
"PAGE_NUMBER" = 163;
0"NC";
1"SG\g";
2"XP2R5V_FPGA\g";
3"XP2R5V_FPGA\g";
4"SG\g";
5"MHZ200CLKN_CLKIN";
6"MHZ200CLKP_CLKIN";
7"FPGA_OUT_MAC_PPS_IN1P";
8"FPGA_OUT_MAC_PPS_IN1N";
9"FPGA_OUT_MAC_PPS_IN0N";
10"FPGA_OUT_MAC_PPS_IN0P";
11"FPGA_IN_MAC_PPS_OUTN";
12"FPGA_IN_MAC_PPS_OUTP";
13"IO_L22P_34";
14"IO_L22N_34";
15"IO_L20P_34";
16"IO_L24N_35";
17"IO_L24P_35";
18"IO_L23N_35";
19"IO_L23P_35";
20"IO_L22N_35";
21"IO_L22P_35";
22"IO_L21N_35";
23"IO_L21P_35";
24"IO_L20N_35";
25"IO_L20P_35";
26"IO_L24P_34";
27"IO_L24N_34";
28"IO_L23N_34";
29"IO_L23P_34";
30"IO_L21P_34";
31"IO_L21N_34";
32"IO_L20N_34";
%"XC7A200T_2FBG484C_FBG484"
"4","(-9800,8050)","0","pld","I1";
;
$LOCATION"U24"
CDS_LOCATION"U24"
$SEC"4"
CDS_SEC"4"
VALUE"XC7A100T-1FGG484I"
CLS_PN"G240-10069-01"
CDS_LIB"pld"
CDS_LMAN_SYM_OUTLINE"0,0,3000,-5400";
"IO_L1P_T0_AD4P_35"
$PN"B1"0;
"IO_L1P_T0_34"
$PN"T1"0;
"IO_L1N_T0_AD4N_35"
$PN"A1"0;
"IO_L1N_T0_34"
$PN"U1"0;
"IO_L8P_T1_AD14P_35"
$PN"H2"0;
"IO_L8P_T1_34"
$PN"AB3"10;
"IO_L8N_T1_AD14N_35"
$PN"G2"0;
"IO_L8N_T1_34"
$PN"AB2"9;
"IO_L7P_T1_AD6P_35"
$PN"K1"0;
"IO_L7P_T1_34"
$PN"AA1"0;
"IO_L7N_T1_AD6N_35"
$PN"J1"0;
"IO_L7N_T1_34"
$PN"AB1"0;
"IO_L6P_T0_35"
$PN"F3"0;
"IO_L6P_T0_34"
$PN"U3"0;
"IO_L6N_T0_VREF_35"
$PN"E3"0;
"IO_L6N_T0_VREF_34"
$PN"V3"0;
"IO_L5P_T0_AD13P_35"
$PN"G1"0;
"IO_L5P_T0_34"
$PN"W1"12;
"IO_L5N_T0_AD13N_35"
$PN"F1"0;
"IO_L5N_T0_34"
$PN"Y1"11;
"IO_L4P_T0_35"
$PN"E2"0;
"IO_L4P_T0_34"
$PN"W2"0;
"IO_L4N_T0_35"
$PN"D2"0;
"IO_L4N_T0_34"
$PN"Y2"0;
"IO_L3P_T0_DQS_AD5P_35"
$PN"E1"0;
"IO_L3P_T0_DQS_34"
$PN"R3"0;
"IO_L3N_T0_DQS_AD5N_35"
$PN"D1"0;
"IO_L3N_T0_DQS_34"
$PN"R2"0;
"IO_L2P_T0_AD12P_35"
$PN"C2"0;
"IO_L2P_T0_34"
$PN"U2"0;
"IO_L2N_T0_AD12N_35"
$PN"B2"0;
"IO_L2N_T0_34"
$PN"V2"0;
"IO_L9P_T1_DQS_AD7P_35"
$PN"K2"0;
"IO_L9P_T1_DQS_34"
$PN"Y3"0;
"IO_L9N_T1_DQS_AD7N_35"
$PN"J2"0;
"IO_L9N_T1_DQS_34"
$PN"AA3"0;
"IO_L15P_T2_DQS_35"
$PN"M1"0;
"IO_L15P_T2_DQS_34"
$PN"W6"0;
"IO_L15N_T2_DQS_35"
$PN"L1"0;
"IO_L15N_T2_DQS_34"
$PN"W5"0;
"IO_L14P_T2_SRCC_35"
$PN"L3"0;
"IO_L14P_T2_SRCC_34"
$PN"T5"0;
"IO_L14N_T2_SRCC_35"
$PN"K3"0;
"IO_L14N_T2_SRCC_34"
$PN"U5"0;
"IO_L13P_T2_MRCC_35"
$PN"K4"0;
"IO_L13P_T2_MRCC_34"
$PN"R4"6;
"IO_L13N_T2_MRCC_35"
$PN"J4"0;
"IO_L13N_T2_MRCC_34"
$PN"T4"5;
"IO_L12P_T1_MRCC_35"
$PN"H4"0;
"IO_L12P_T1_MRCC_34"
$PN"V4"0;
"IO_L12N_T1_MRCC_35"
$PN"G4"0;
"IO_L12N_T1_MRCC_34"
$PN"W4"0;
"IO_L11P_T1_SRCC_35"
$PN"H3"0;
"IO_L11P_T1_SRCC_34"
$PN"Y4"0;
"IO_L11N_T1_SRCC_35"
$PN"G3"0;
"IO_L11N_T1_SRCC_34"
$PN"AA4"0;
"IO_L10P_T1_AD15P_35"
$PN"J5"0;
"IO_L10P_T1_34"
$PN"AA5"7;
"IO_L10N_T1_AD15N_35"
$PN"H5"0;
"IO_L10N_T1_34"
$PN"AB5"8;
"IO_25_35"
$PN"L6"0;
"IO_25_34"
$PN"U7"0;
"IO_0_35"
$PN"F4"0;
"IO_0_34"
$PN"T3"0;
"IO_L16P_T2_35"
$PN"M3"0;
"IO_L16P_T2_34"
$PN"U6"0;
"IO_L16N_T2_35"
$PN"M2"0;
"IO_L16N_T2_34"
$PN"V5"0;
"IO_L24P_T3_35"
$PN"P6"17;
"IO_L24P_T3_34"
$PN"W9"26;
"IO_L24N_T3_35"
$PN"N5"16;
"IO_L24N_T3_34"
$PN"Y9"27;
"IO_L23P_T3_35"
$PN"M6"19;
"IO_L23P_T3_34"
$PN"Y8"29;
"IO_L23N_T3_35"
$PN"M5"18;
"IO_L23N_T3_34"
$PN"Y7"28;
"IO_L22P_T3_35"
$PN"P2"21;
"IO_L22P_T3_34"
$PN"AA8"13;
"IO_L22N_T3_35"
$PN"N2"20;
"IO_L22N_T3_34"
$PN"AB8"14;
"IO_L21P_T3_DQS_35"
$PN"P5"23;
"IO_L21P_T3_DQS_34"
$PN"V9"30;
"IO_L21N_T3_DQS_35"
$PN"P4"22;
"IO_L21N_T3_DQS_34"
$PN"V8"31;
"IO_L20P_T3_35"
$PN"R1"25;
"IO_L20P_T3_34"
$PN"AB7"15;
"IO_L20N_T3_35"
$PN"P1"24;
"IO_L20N_T3_34"
$PN"AB6"32;
"IO_L19P_T3_35"
$PN"N4"0;
"IO_L19P_T3_34"
$PN"V7"0;
"IO_L19N_T3_VREF_35"
$PN"N3"0;
"IO_L19N_T3_VREF_34"
$PN"W7"0;
"IO_L18P_T2_35"
$PN"L5"0;
"IO_L18P_T2_34"
$PN"Y6"0;
"IO_L18N_T2_35"
$PN"L4"0;
"IO_L18N_T2_34"
$PN"AA6"0;
"IO_L17P_T2_35"
$PN"K6"0;
"IO_L17P_T2_34"
$PN"R6"0;
"IO_L17N_T2_35"
$PN"J6"0;
"IO_L17N_T2_34"
$PN"T6"0;
%"RESISTOR"
"2","(-3850,5350)","1","passive","I120";
;
$LOCATION"R355"
CDS_LOCATION"R355"
$SEC"1"
CDS_SEC"1"
PACKAGE"0402"
VALUE"10KOHM"
CDS_LMAN_SYM_OUTLINE"-50,50,50,-100"
CDS_LIB"passive"
CLS_PN"G155-11002-01"
TOLERANCE"1%";
"1"
$PN"1"5;
"2"
$PN"2"3;
%"GND_SG"
"1","(-3100,4700)","0","cls","I124";
;
HDL_POWER"SG"
CDS_LMAN_SYM_OUTLINE"0,0,100,-50"
CDS_LIB"cls"
BODY_TYPE"PLUMBING";
"SGND"4;
%"VCC"
"1","(-3000,5400)","0","cls","I125";
;
VOLTAGE"2.5V"
HDL_POWER"XP2R5V_FPGA"
CDS_LIB"cls"
CDS_LMAN_SYM_OUTLINE"-250,250,250,-250"
BODY_TYPE"PLUMBING";
"$PIN0"3;
%"RESISTOR"
"2","(-3850,5250)","1","passive","I126";
;
LOCATION"R358"
$SEC"1"
CDS_SEC"1"
PACKAGE"0402"
VALUE"10KOHM"
CDS_LMAN_SYM_OUTLINE"-50,50,50,-100"
CDS_LIB"passive"
CLS_PN"G155-11002-01"
TOLERANCE"1%";
"1"
$PN"1"6;
"2"
$PN"2"3;
%"RESISTOR"
"2","(-3850,4950)","1","passive","I127";
;
LOCATION"R359"
$SEC"1"
CDS_SEC"1"
VALUE"10KOHM"
PACKAGE"0402"
CDS_LMAN_SYM_OUTLINE"-50,50,50,-100"
CDS_LIB"passive"
CLS_PN"G155-11002-01"
TOLERANCE"1%";
"1"
$PN"1"6;
"2"
$PN"2"4;
%"RESISTOR"
"2","(-3850,4850)","1","passive","I128";
;
LOCATION"R360"
$SEC"1"
CDS_SEC"1"
PACKAGE"0402"
VALUE"10KOHM"
CDS_LMAN_SYM_OUTLINE"-50,50,50,-100"
CDS_LIB"passive"
CLS_PN"G155-11002-01"
TOLERANCE"1%";
"1"
$PN"1"5;
"2"
$PN"2"4;
%"VCC"
"1","(-3000,7000)","0","cls","I130";
;
HDL_POWER"XP2R5V_FPGA"
VOLTAGE"2.5V"
BODY_TYPE"PLUMBING"
CDS_LMAN_SYM_OUTLINE"-250,250,250,-250"
CDS_LIB"cls";
"$PIN0"2;
%"GND_SG"
"1","(-3100,6300)","0","cls","I131";
;
HDL_POWER"SG"
BODY_TYPE"PLUMBING"
CDS_LMAN_SYM_OUTLINE"0,0,100,-50"
CDS_LIB"cls";
"SGND"1;
%"RESISTOR"
"2","(-3850,6950)","1","passive","I132";
;
$LOCATION"R438"
CDS_LOCATION"R438"
$SEC"1"
CDS_SEC"1"
VALUE"10KOHM"
PACKAGE"0402"
TOLERANCE"1%"
CLS_PN"G155-11002-01"
CDS_LMAN_SYM_OUTLINE"-50,50,50,-100"
CDS_LIB"passive";
"1"
$PN"1"11;
"2"
$PN"2"2;
%"RESISTOR"
"2","(-3850,6850)","1","passive","I133";
;
$LOCATION"R439"
CDS_LOCATION"R439"
$SEC"1"
CDS_SEC"1"
VALUE"10KOHM"
PACKAGE"0402"
TOLERANCE"1%"
CLS_PN"G155-11002-01"
CDS_LMAN_SYM_OUTLINE"-50,50,50,-100"
CDS_LIB"passive";
"1"
$PN"1"12;
"2"
$PN"2"2;
%"RESISTOR"
"2","(-3850,6450)","1","passive","I134";
;
$LOCATION"R441"
CDS_LOCATION"R441"
$SEC"1"
CDS_SEC"1"
VALUE"10KOHM"
PACKAGE"0402"
TOLERANCE"1%"
CLS_PN"G155-11002-01"
CDS_LMAN_SYM_OUTLINE"-50,50,50,-100"
CDS_LIB"passive";
"1"
$PN"1"11;
"2"
$PN"2"1;
%"RESISTOR"
"2","(-3850,6550)","1","passive","I135";
;
$LOCATION"R440"
CDS_LOCATION"R440"
$SEC"1"
CDS_SEC"1"
VALUE"10KOHM"
PACKAGE"0402"
TOLERANCE"1%"
CLS_PN"G155-11002-01"
CDS_LMAN_SYM_OUTLINE"-50,50,50,-100"
CDS_LIB"passive";
"1"
$PN"1"12;
"2"
$PN"2"1;
%"RESISTOR"
"1","(-5600,5250)","0","passive","I36";
;
$LOCATION"R278"
CDS_LOCATION"R278"
$SEC"1"
CDS_SEC"1"
VALUE"100OHM"
PACKAGE"0402"
TOLERANCE"1%"
CLS_PN"G155-11000-01"
CDS_LMAN_SYM_OUTLINE"-50,50,100,-50"
CDS_LIB"passive";
"1"
$PN"1"6;
"2"
$PN"2"5;
%"RESISTOR"
"1","(-5450,5850)","0","passive","I37";
;
$LOCATION"R277"
CDS_LOCATION"R277"
$SEC"1"
CDS_SEC"1"
NO_ASSY"TRUE"
VALUE"100OHM"
PACKAGE"0402"
TOLERANCE"1%"
CLS_PN"G155-11000-01"
CDS_LMAN_SYM_OUTLINE"-50,50,100,-50"
CDS_LIB"passive";
"1"
$PN"1"7;
"2"
$PN"2"8;
%"RESISTOR"
"1","(-5450,6250)","0","passive","I38";
;
$LOCATION"R276"
CDS_LOCATION"R276"
$SEC"1"
CDS_SEC"1"
PACKAGE"0402"
VALUE"100OHM"
NO_ASSY"TRUE"
TOLERANCE"1%"
CLS_PN"G155-11000-01"
CDS_LMAN_SYM_OUTLINE"-50,50,100,-50"
CDS_LIB"passive";
"1"
$PN"1"10;
"2"
$PN"2"9;
%"RESISTOR"
"1","(-5550,6850)","0","passive","I39";
;
$LOCATION"R275"
CDS_LOCATION"R275"
$SEC"1"
CDS_SEC"1"
VALUE"100OHM"
PACKAGE"0402"
NO_ASSY"TRUE"
CLS_PN"G155-11000-01"
CDS_LMAN_SYM_OUTLINE"-50,50,100,-50"
CDS_LIB"passive"
TOLERANCE"1%";
"1"
$PN"1"12;
"2"
$PN"2"11;
END.
